(kicad_pcb
	(version 20260206)
	(generator "pcbnew")
	(generator_version "10.0")
	(general
		(thickness 1.6)
		(legacy_teardrops no)
	)
	(paper "A4")
	(title_block
		(title "fcb — 12433-1M.1206WZS1330.brd")
		(comment 1 "Open Vault / Knox (Wiwynn) / footprints 165-170 of 495")
	)
	(layers
		(0 "F.Cu" signal "TOP")
		(4 "In1.Cu" signal "L2GND")
		(6 "In2.Cu" signal "L3VCC")
		(2 "B.Cu" signal "BOTTOM")
		(9 "F.Adhes" user "F.Adhesive")
		(11 "B.Adhes" user "B.Adhesive")
		(13 "F.Paste" user "Package Geometry/Pastemask Top")
		(15 "B.Paste" user "Package Geometry/Pastemask Bottom")
		(5 "F.SilkS" user "Ref Des/Silkscreen Top")
		(7 "B.SilkS" user "Ref Des/Silkscreen Bottom")
		(1 "F.Mask" user "Board Geometry/Soldermask Top")
		(3 "B.Mask" user "Board Geometry/Soldermask Bottom")
		(17 "Dwgs.User" user "User.Drawings")
		(19 "Cmts.User" user "User.Comments")
		(21 "Eco1.User" user "User.Eco1")
		(23 "Eco2.User" user "User.Eco2")
		(25 "Edge.Cuts" user "Board Geometry/Outline")
		(27 "Margin" user)
		(31 "F.CrtYd" user "Package Geometry/Place Bound Top")
		(29 "B.CrtYd" user "Package Geometry/Place Bound Bottom")
		(35 "F.Fab" user "Ref Des/Assembly Top")
		(33 "B.Fab" user "Ref Des/Assembly Bottom")
	)
	(footprint ""
		(layer "F.Cu")
		(at 28.8544 -357.6828 90)
		(property "Reference" "R366"
			(at 0 0 90)
			(layer "F.SilkS")
			(hide yes)
			(effects
				(font
					(size 1.27 1.27)
				)
			)
		)
		(property "Value" "10KR2F-2-GP"
			(at 0.064008 -3.993896 90)
			(unlocked yes)
			(layer "F.Fab")
			(hide yes)
			(effects
				(font
					(size 1.016 1.016)
					(thickness 0.1524)
				)
			)
		)
		(property "Device Type" "R402H16"
			(at 0.064008 -5.517896 90)
			(unlocked yes)
			(layer "F.Fab")
			(hide yes)
			(effects
				(font
					(size 1.016 1.016)
					(thickness 0.1524)
				)
			)
		)
		(duplicate_pad_numbers_are_jumpers no)
		(fp_line
			(start 0.508 -0.9398)
			(end -0.508 -0.9398)
			(stroke
				(width 0.1524)
				(type default)
			)
			(layer "F.SilkS")
		)
		(fp_line
			(start -0.508 -0.9398)
			(end -0.508 0.9398)
			(stroke
				(width 0.1524)
				(type default)
			)
			(layer "F.SilkS")
		)
		(fp_rect
			(start -0.508 0.9398)
			(end 0.508 -0.9398)
			(stroke
				(width 0)
				(type default)
			)
			(fill no)
			(layer "F.CrtYd")
		)
		(fp_rect
			(start -0.508 0.9398)
			(end 0.508 -0.9398)
			(stroke
				(width 0)
				(type default)
			)
			(fill no)
			(layer "F.Fab")
		)
		(pad "1" smd custom
			(at 0 -0.4445 90)
			(size 0.1397 0.1397)
			(layers "F.Cu" "F.Mask" "F.Paste")
			(net "P3V3")
			(options
				(clearance outline)
				(anchor circle)
			)
			(primitives
				(gr_poly
					(pts
						(arc
							(start -0.1778 -0.2794)
							(mid -0.249642 -0.249642)
							(end -0.2794 -0.1778)
						)
						(arc
							(start -0.2794 0.1778)
							(mid -0.249642 0.249642)
							(end -0.1778 0.2794)
						)
						(arc
							(start 0.1778 0.2794)
							(mid 0.249642 0.249642)
							(end 0.2794 0.1778)
						)
						(arc
							(start 0.2794 -0.1778)
							(mid 0.249642 -0.249642)
							(end 0.1778 -0.2794)
						)
					)
					(width 0)
					(fill yes)
				)
			)
		)
		(pad "2" smd custom
			(at 0 0.4445 90)
			(size 0.1397 0.1397)
			(layers "F.Cu" "F.Mask" "F.Paste")
			(net "TEMP_ALM#")
			(options
				(clearance outline)
				(anchor circle)
			)
			(primitives
				(gr_poly
					(pts
						(arc
							(start -0.1778 -0.2794)
							(mid -0.249642 -0.249642)
							(end -0.2794 -0.1778)
						)
						(arc
							(start -0.2794 0.1778)
							(mid -0.249642 0.249642)
							(end -0.1778 0.2794)
						)
						(arc
							(start 0.1778 0.2794)
							(mid 0.249642 0.249642)
							(end 0.2794 0.1778)
						)
						(arc
							(start 0.2794 -0.1778)
							(mid 0.249642 -0.249642)
							(end 0.1778 -0.2794)
						)
					)
					(width 0)
					(fill yes)
				)
			)
		)
	)
	(footprint ""
		(layer "F.Cu")
		(at 26.6446 -167.767 180)
		(property "Reference" "R163"
			(at 0 0 180)
			(layer "F.SilkS")
			(hide yes)
			(effects
				(font
					(size 1.27 1.27)
				)
			)
		)
		(property "Value" "0R2J-2-GP"
			(at 0.064008 -3.993896 180)
			(unlocked yes)
			(layer "F.Fab")
			(hide yes)
			(effects
				(font
					(size 1.016 1.016)
					(thickness 0.1524)
				)
			)
		)
		(property "Device Type" "R402H16"
			(at 0.064008 -5.517896 180)
			(unlocked yes)
			(layer "F.Fab")
			(hide yes)
			(effects
				(font
					(size 1.016 1.016)
					(thickness 0.1524)
				)
			)
		)
		(duplicate_pad_numbers_are_jumpers no)
		(fp_line
			(start 0.508 -0.9398)
			(end -0.508 -0.9398)
			(stroke
				(width 0.1524)
				(type default)
			)
			(layer "F.SilkS")
		)
		(fp_line
			(start -0.508 -0.9398)
			(end -0.508 0.9398)
			(stroke
				(width 0.1524)
				(type default)
			)
			(layer "F.SilkS")
		)
		(fp_rect
			(start -0.508 0.9398)
			(end 0.508 -0.9398)
			(stroke
				(width 0)
				(type default)
			)
			(fill no)
			(layer "F.CrtYd")
		)
		(fp_rect
			(start -0.508 0.9398)
			(end 0.508 -0.9398)
			(stroke
				(width 0)
				(type default)
			)
			(fill no)
			(layer "F.Fab")
		)
		(pad "1" smd custom
			(at 0 -0.4445 180)
			(size 0.1397 0.1397)
			(layers "F.Cu" "F.Mask" "F.Paste")
			(net "NCT7904D_PWM3")
			(options
				(clearance outline)
				(anchor circle)
			)
			(primitives
				(gr_poly
					(pts
						(arc
							(start -0.1778 -0.2794)
							(mid -0.249642 -0.249642)
							(end -0.2794 -0.1778)
						)
						(arc
							(start -0.2794 0.1778)
							(mid -0.249642 0.249642)
							(end -0.1778 0.2794)
						)
						(arc
							(start 0.1778 0.2794)
							(mid 0.249642 0.249642)
							(end 0.2794 0.1778)
						)
						(arc
							(start 0.2794 -0.1778)
							(mid 0.249642 -0.249642)
							(end 0.1778 -0.2794)
						)
					)
					(width 0)
					(fill yes)
				)
			)
		)
		(pad "2" smd custom
			(at 0 0.4445 180)
			(size 0.1397 0.1397)
			(layers "F.Cu" "F.Mask" "F.Paste")
			(net "PWM_BUFFER_IN_FAN5_FAN6")
			(options
				(clearance outline)
				(anchor circle)
			)
			(primitives
				(gr_poly
					(pts
						(arc
							(start -0.1778 -0.2794)
							(mid -0.249642 -0.249642)
							(end -0.2794 -0.1778)
						)
						(arc
							(start -0.2794 0.1778)
							(mid -0.249642 0.249642)
							(end -0.1778 0.2794)
						)
						(arc
							(start 0.1778 0.2794)
							(mid 0.249642 0.249642)
							(end 0.2794 0.1778)
						)
						(arc
							(start 0.2794 -0.1778)
							(mid 0.249642 -0.249642)
							(end 0.1778 -0.2794)
						)
					)
					(width 0)
					(fill yes)
				)
			)
		)
	)
	(footprint ""
		(layer "F.Cu")
		(at 22.1996 -146.2786 180)
		(property "Reference" "PC93"
			(at 0 0 180)
			(layer "F.SilkS")
			(hide yes)
			(effects
				(font
					(size 1.27 1.27)
				)
			)
		)
		(property "Value" "SC220P50V2KX-3GP"
			(at 1.1811 -2.7051 180)
			(unlocked yes)
			(layer "F.Fab")
			(hide yes)
			(effects
				(font
					(size 1.016 1.016)
					(thickness 0.1524)
				)
			)
		)
		(property "Device Type" "C402H22"
			(at 1.1811 -4.2291 180)
			(unlocked yes)
			(layer "F.Fab")
			(hide yes)
			(effects
				(font
					(size 1.016 1.016)
					(thickness 0.1524)
				)
			)
		)
		(duplicate_pad_numbers_are_jumpers no)
		(fp_rect
			(start -0.4318 0.9525)
			(end 0.4318 -0.9525)
			(stroke
				(width 0)
				(type default)
			)
			(fill no)
			(layer "F.CrtYd")
		)
		(fp_rect
			(start -0.4318 0.9525)
			(end 0.4318 -0.9525)
			(stroke
				(width 0)
				(type default)
			)
			(fill no)
			(layer "F.Fab")
		)
		(pad "1" smd custom
			(at 0 -0.4445 180)
			(size 0.1524 0.1524)
			(layers "F.Cu" "F.Mask" "F.Paste")
			(net "P12VU_2490_VREF")
			(options
				(clearance outline)
				(anchor circle)
			)
			(primitives
				(gr_poly
					(pts
						(arc
							(start 0.3048 -0.2032)
							(mid 0.275042 -0.275042)
							(end 0.2032 -0.3048)
						)
						(arc
							(start -0.2032 -0.3048)
							(mid -0.275042 -0.275042)
							(end -0.3048 -0.2032)
						)
						(arc
							(start -0.3048 0.2032)
							(mid -0.275042 0.275042)
							(end -0.2032 0.3048)
						)
						(arc
							(start 0.2032 0.3048)
							(mid 0.275042 0.275042)
							(end 0.3048 0.2032)
						)
					)
					(width 0)
					(fill yes)
				)
			)
		)
		(pad "2" smd custom
			(at 0 0.4445 180)
			(size 0.1524 0.1524)
			(layers "F.Cu" "F.Mask" "F.Paste")
			(net "GND")
			(options
				(clearance outline)
				(anchor circle)
			)
			(primitives
				(gr_poly
					(pts
						(arc
							(start 0.3048 -0.2032)
							(mid 0.275042 -0.275042)
							(end 0.2032 -0.3048)
						)
						(arc
							(start -0.2032 -0.3048)
							(mid -0.275042 -0.275042)
							(end -0.3048 -0.2032)
						)
						(arc
							(start -0.3048 0.2032)
							(mid -0.275042 0.275042)
							(end -0.2032 0.3048)
						)
						(arc
							(start 0.2032 0.3048)
							(mid 0.275042 0.275042)
							(end 0.3048 0.2032)
						)
					)
					(width 0)
					(fill yes)
				)
			)
		)
	)
	(footprint ""
		(layer "F.Cu")
		(at 32.766 -381 180)
		(property "Reference" "PR22"
			(at 0 0 180)
			(layer "F.SilkS")
			(hide yes)
			(effects
				(font
					(size 1.27 1.27)
				)
			)
		)
		(property "Value" "10R2F-L-GP"
			(at 0.064008 -3.993896 180)
			(unlocked yes)
			(layer "F.Fab")
			(hide yes)
			(effects
				(font
					(size 1.016 1.016)
					(thickness 0.1524)
				)
			)
		)
		(property "Device Type" "R402H14"
			(at 0.064008 -5.517896 180)
			(unlocked yes)
			(layer "F.Fab")
			(hide yes)
			(effects
				(font
					(size 1.016 1.016)
					(thickness 0.1524)
				)
			)
		)
		(duplicate_pad_numbers_are_jumpers no)
		(fp_line
			(start 0.508 -0.9398)
			(end -0.508 -0.9398)
			(stroke
				(width 0.1524)
				(type default)
			)
			(layer "F.SilkS")
		)
		(fp_line
			(start -0.508 -0.9398)
			(end -0.508 0.9398)
			(stroke
				(width 0.1524)
				(type default)
			)
			(layer "F.SilkS")
		)
		(fp_rect
			(start -0.508 0.9398)
			(end 0.508 -0.9398)
			(stroke
				(width 0)
				(type default)
			)
			(fill no)
			(layer "F.CrtYd")
		)
		(fp_rect
			(start -0.508 0.9398)
			(end 0.508 -0.9398)
			(stroke
				(width 0)
				(type default)
			)
			(fill no)
			(layer "F.Fab")
		)
		(pad "1" smd custom
			(at 0 -0.4445 180)
			(size 0.1397 0.1397)
			(layers "F.Cu" "F.Mask" "F.Paste")
			(net "ADM1276_SENSE-")
			(options
				(clearance outline)
				(anchor circle)
			)
			(primitives
				(gr_poly
					(pts
						(arc
							(start -0.1778 -0.2794)
							(mid -0.249642 -0.249642)
							(end -0.2794 -0.1778)
						)
						(arc
							(start -0.2794 0.1778)
							(mid -0.249642 0.249642)
							(end -0.1778 0.2794)
						)
						(arc
							(start 0.1778 0.2794)
							(mid 0.249642 0.249642)
							(end 0.2794 0.1778)
						)
						(arc
							(start 0.2794 -0.1778)
							(mid 0.249642 -0.249642)
							(end 0.1778 -0.2794)
						)
					)
					(width 0)
					(fill yes)
				)
			)
		)
		(pad "2" smd custom
			(at 0 0.4445 180)
			(size 0.1397 0.1397)
			(layers "F.Cu" "F.Mask" "F.Paste")
			(net "SENSE-_R2")
			(options
				(clearance outline)
				(anchor circle)
			)
			(primitives
				(gr_poly
					(pts
						(arc
							(start -0.1778 -0.2794)
							(mid -0.249642 -0.249642)
							(end -0.2794 -0.1778)
						)
						(arc
							(start -0.2794 0.1778)
							(mid -0.249642 0.249642)
							(end -0.1778 0.2794)
						)
						(arc
							(start 0.1778 0.2794)
							(mid 0.249642 0.249642)
							(end 0.2794 0.1778)
						)
						(arc
							(start 0.2794 -0.1778)
							(mid 0.249642 -0.249642)
							(end 0.1778 -0.2794)
						)
					)
					(width 0)
					(fill yes)
				)
			)
		)
	)
	(footprint ""
		(layer "F.Cu")
		(at 7.949946 -88.535002 -90)
		(property "Reference" "LED5"
			(at 0 0 270)
			(layer "F.SilkS")
			(hide yes)
			(effects
				(font
					(size 1.27 1.27)
				)
			)
		)
		(property "Value" "LED-RB-6-GP"
			(at -4.6736 3.8354 270)
			(unlocked yes)
			(layer "F.Fab")
			(hide yes)
			(effects
				(font
					(size 1.016 1.016)
					(thickness 0.1524)
				)
			)
		)
		(property "Device Type" "LED-100-3P-067106H325"
			(at -4.6736 2.3114 270)
			(unlocked yes)
			(layer "F.Fab")
			(hide yes)
			(effects
				(font
					(size 1.016 1.016)
					(thickness 0.1524)
				)
			)
		)
		(duplicate_pad_numbers_are_jumpers no)
		(fp_line
			(start -1.7526 10.414)
			(end -1.7526 6.6548)
			(stroke
				(width 0.1524)
				(type default)
			)
			(layer "F.SilkS")
		)
		(fp_line
			(start 1.7526 10.414)
			(end -1.7526 10.414)
			(stroke
				(width 0.1524)
				(type default)
			)
			(layer "F.SilkS")
		)
		(fp_line
			(start -3.6068 6.6548)
			(end -3.6068 -0.889)
			(stroke
				(width 0.1524)
				(type default)
			)
			(layer "F.SilkS")
		)
		(fp_line
			(start -1.7526 6.6548)
			(end -3.6068 6.6548)
			(stroke
				(width 0.1524)
				(type default)
			)
			(layer "F.SilkS")
		)
		(fp_line
			(start 1.7526 6.6548)
			(end 1.7526 10.414)
			(stroke
				(width 0.1524)
				(type default)
			)
			(layer "F.SilkS")
		)
		(fp_line
			(start 3.6068 6.6548)
			(end 1.7526 6.6548)
			(stroke
				(width 0.1524)
				(type default)
			)
			(layer "F.SilkS")
		)
		(fp_line
			(start -3.6068 -0.889)
			(end 3.6068 -0.889)
			(stroke
				(width 0.1524)
				(type default)
			)
			(layer "F.SilkS")
		)
		(fp_line
			(start 3.6068 -0.889)
			(end 3.6068 6.6548)
			(stroke
				(width 0.1524)
				(type default)
			)
			(layer "F.SilkS")
		)
		(fp_circle
			(center -2.54 0)
			(end -2.54 -0.9906)
			(stroke
				(width 0.3048)
				(type default)
			)
			(fill no)
			(layer "F.SilkS")
		)
		(fp_circle
			(center 0 0)
			(end 0 -0.9906)
			(stroke
				(width 0.3048)
				(type default)
			)
			(fill no)
			(layer "F.SilkS")
		)
		(fp_circle
			(center 2.54 0)
			(end 2.54 -0.9906)
			(stroke
				(width 0.3048)
				(type default)
			)
			(fill no)
			(layer "F.SilkS")
		)
		(fp_poly
			(pts
				(xy -1.4986 10.1473) (xy -1.4986 6.4008) (xy -3.3528 6.4008) (xy -3.3528 -0.3937) (xy 3.3528 -0.3937)
				(xy 3.3528 6.4008) (xy 1.4986 6.4008) (xy 1.4986 10.1473)
			)
			(stroke
				(width 0)
				(type default)
			)
			(fill no)
			(layer "F.CrtYd")
		)
		(fp_poly
			(pts
				(xy -2.0066 10.668) (xy 2.0066 10.668) (xy 2.0066 6.9088) (xy 3.8608 6.9088) (xy 3.8608 2.2098)
				(xy 3.3528 2.2098) (xy 3.3528 6.4008) (xy 1.4986 6.4008) (xy 1.4986 10.1473) (xy -1.4986 10.1473)
				(xy -1.4986 6.4008) (xy -3.3528 6.4008) (xy -3.3528 -0.3937) (xy 3.3528 -0.3937) (xy 3.3528 2.1971)
				(xy 3.8608 2.1971) (xy 3.8608 -1.143) (xy -3.8608 -1.143) (xy -3.8608 6.9088) (xy -2.0066 6.9088)
			)
			(stroke
				(width 0)
				(type default)
			)
			(fill no)
			(layer "F.CrtYd")
		)
		(fp_poly
			(pts
				(xy -2.0066 10.668) (xy -2.0066 6.9088) (xy -3.8608 6.9088) (xy -3.8608 -1.143) (xy 3.8608 -1.143)
				(xy 3.8608 6.9088) (xy 2.0066 6.9088) (xy 2.0066 10.668)
			)
			(stroke
				(width 0)
				(type default)
			)
			(fill no)
			(layer "F.Fab")
		)
		(pad "1" thru_hole circle
			(at 2.54 0 270)
			(size 1.27 1.27)
			(drill 0.889)
			(layers "*.Cu" "*.Mask")
			(remove_unused_layers no)
			(net "LED_DR_LED4_BLUE")
			(clearance 0.1651)
			(thermal_gap 0.1651)
		)
		(pad "2" thru_hole circle
			(at 0 0 270)
			(size 1.27 1.27)
			(drill 0.889)
			(layers "*.Cu" "*.Mask")
			(remove_unused_layers no)
			(net "LED_DR_LED4_K")
			(clearance 0.1651)
			(thermal_gap 0.1651)
		)
		(pad "3" thru_hole circle
			(at -2.54 0 270)
			(size 1.27 1.27)
			(drill 0.889)
			(layers "*.Cu" "*.Mask")
			(remove_unused_layers no)
			(net "LED_DR_LED4")
			(clearance 0.1651)
			(thermal_gap 0.1651)
		)
	)
	(footprint ""
		(layer "F.Cu")
		(at 20.7518 -173.2788 -90)
		(property "Reference" "R183"
			(at 0 0 270)
			(layer "F.SilkS")
			(hide yes)
			(effects
				(font
					(size 1.27 1.27)
				)
			)
		)
		(property "Value" "0R2J-2-GP"
			(at 0.064008 -3.993896 270)
			(unlocked yes)
			(layer "F.Fab")
			(hide yes)
			(effects
				(font
					(size 1.016 1.016)
					(thickness 0.1524)
				)
			)
		)
		(property "Device Type" "R402H16"
			(at 0.064008 -5.517896 270)
			(unlocked yes)
			(layer "F.Fab")
			(hide yes)
			(effects
				(font
					(size 1.016 1.016)
					(thickness 0.1524)
				)
			)
		)
		(duplicate_pad_numbers_are_jumpers no)
		(fp_line
			(start -0.508 -0.9398)
			(end -0.508 0.9398)
			(stroke
				(width 0.1524)
				(type default)
			)
			(layer "F.SilkS")
		)
		(fp_line
			(start 0.508 -0.9398)
			(end -0.508 -0.9398)
			(stroke
				(width 0.1524)
				(type default)
			)
			(layer "F.SilkS")
		)
		(fp_rect
			(start -0.508 0.9398)
			(end 0.508 -0.9398)
			(stroke
				(width 0)
				(type default)
			)
			(fill no)
			(layer "F.CrtYd")
		)
		(fp_rect
			(start -0.508 0.9398)
			(end 0.508 -0.9398)
			(stroke
				(width 0)
				(type default)
			)
			(fill no)
			(layer "F.Fab")
		)
		(pad "1" smd custom
			(at 0 -0.4445 270)
			(size 0.1397 0.1397)
			(layers "F.Cu" "F.Mask" "F.Paste")
			(net "THERMHOT#")
			(options
				(clearance outline)
				(anchor circle)
			)
			(primitives
				(gr_poly
					(pts
						(arc
							(start -0.1778 -0.2794)
							(mid -0.249642 -0.249642)
							(end -0.2794 -0.1778)
						)
						(arc
							(start -0.2794 0.1778)
							(mid -0.249642 0.249642)
							(end -0.1778 0.2794)
						)
						(arc
							(start 0.1778 0.2794)
							(mid 0.249642 0.249642)
							(end 0.2794 0.1778)
						)
						(arc
							(start 0.2794 -0.1778)
							(mid 0.249642 -0.249642)
							(end 0.1778 -0.2794)
						)
					)
					(width 0)
					(fill yes)
				)
			)
		)
		(pad "2" smd custom
			(at 0 0.4445 270)
			(size 0.1397 0.1397)
			(layers "F.Cu" "F.Mask" "F.Paste")
			(net "THERMHOT#_R")
			(options
				(clearance outline)
				(anchor circle)
			)
			(primitives
				(gr_poly
					(pts
						(arc
							(start -0.1778 -0.2794)
							(mid -0.249642 -0.249642)
							(end -0.2794 -0.1778)
						)
						(arc
							(start -0.2794 0.1778)
							(mid -0.249642 0.249642)
							(end -0.1778 0.2794)
						)
						(arc
							(start 0.1778 0.2794)
							(mid 0.249642 0.249642)
							(end 0.2794 0.1778)
						)
						(arc
							(start 0.2794 -0.1778)
							(mid 0.249642 -0.249642)
							(end 0.1778 -0.2794)
						)
					)
					(width 0)
					(fill yes)
				)
			)
		)
	)
)
